(kicad_pcb
	(version 20260206)
	(generator "pcbnew")
	(generator_version "10.0")
	(general
		(thickness 1.6)
		(legacy_teardrops no)
	)
	(paper "A4")
	(title_block
		(title "01162023_DA0F0TEBIF0_F0T_Expander_BD_F_brd_V02_OCP.brd")
		(comment 1 "Grand Teton / footprints 5253-5258 of 9728")
	)
	(layers
		(0 "F.Cu" signal "TOP")
		(4 "In1.Cu" signal "GND")
		(6 "In2.Cu" signal "VCC")
		(8 "In3.Cu" signal "VCC1")
		(10 "In4.Cu" signal "GND1")
		(12 "In5.Cu" signal "IN1")
		(14 "In6.Cu" signal "GND2")
		(16 "In7.Cu" signal "IN2")
		(18 "In8.Cu" signal "GND3")
		(20 "In9.Cu" signal "IN3")
		(22 "In10.Cu" signal "GND4")
		(24 "In11.Cu" signal "IN4")
		(26 "In12.Cu" signal "GND5")
		(28 "In13.Cu" signal "IN5")
		(30 "In14.Cu" signal "GND6")
		(32 "In15.Cu" signal "IN6")
		(34 "In16.Cu" signal "GND7")
		(2 "B.Cu" signal "BOTTOM")
		(9 "F.Adhes" user "F.Adhesive")
		(11 "B.Adhes" user "B.Adhesive")
		(13 "F.Paste" user "Package Geometry/Pastemask Top")
		(15 "B.Paste" user "Package Geometry/Pastemask Bottom")
		(5 "F.SilkS" user "Ref Des/Silkscreen Top")
		(7 "B.SilkS" user "Ref Des/Silkscreen Bottom")
		(1 "F.Mask" user "Board Geometry/Soldermask Top")
		(3 "B.Mask" user "Board Geometry/Soldermask Bottom")
		(17 "Dwgs.User" user "User.Drawings")
		(19 "Cmts.User" user "User.Comments")
		(21 "Eco1.User" user "User.Eco1")
		(23 "Eco2.User" user "User.Eco2")
		(25 "Edge.Cuts" user "Board Geometry/Outline")
		(27 "Margin" user)
		(31 "F.CrtYd" user "Package Geometry/Place Bound Top")
		(29 "B.CrtYd" user "Package Geometry/Place Bound Bottom")
		(35 "F.Fab" user "Ref Des/Assembly Top")
		(33 "B.Fab" user "Ref Des/Assembly Bottom")
	)
	(footprint ""
		(layer "F.Cu")
		(at 280.227786 -35.876738)
		(property "Reference" "R6094"
			(at 0 0 0)
			(layer "F.SilkS")
			(hide yes)
			(effects
				(font
					(size 1.27 1.27)
				)
			)
		)
		(property "Value" ""
			(at 0 0 0)
			(layer "F.Fab")
			(effects
				(font
					(size 1.27 1.27)
				)
			)
		)
		(duplicate_pad_numbers_are_jumpers no)
		(fp_line
			(start -0.7874 -0.4064)
			(end 0.7874 -0.4064)
			(stroke
				(width 0.1524)
				(type default)
			)
			(layer "F.SilkS")
		)
		(fp_line
			(start -0.7874 0.4064)
			(end -0.7874 -0.4064)
			(stroke
				(width 0.1524)
				(type default)
			)
			(layer "F.SilkS")
		)
		(fp_line
			(start 0.7874 -0.4064)
			(end 0.7874 0.4064)
			(stroke
				(width 0.1524)
				(type default)
			)
			(layer "F.SilkS")
		)
		(fp_line
			(start 0.7874 0.4064)
			(end -0.7874 0.4064)
			(stroke
				(width 0.1524)
				(type default)
			)
			(layer "F.SilkS")
		)
		(fp_line
			(start -0.67945 -0.305054)
			(end -0.12065 -0.305054)
			(stroke
				(width 0.1)
				(type default)
			)
			(layer "F.Fab")
		)
		(fp_line
			(start -0.67945 0.3048)
			(end -0.67945 -0.305054)
			(stroke
				(width 0.1)
				(type default)
			)
			(layer "F.Fab")
		)
		(fp_line
			(start -0.12065 -0.305054)
			(end -0.12065 -0.2794)
			(stroke
				(width 0.1)
				(type default)
			)
			(layer "F.Fab")
		)
		(fp_line
			(start -0.12065 -0.2794)
			(end 0.12065 -0.2794)
			(stroke
				(width 0.1)
				(type default)
			)
			(layer "F.Fab")
		)
		(fp_line
			(start -0.12065 0.2794)
			(end -0.12065 0.3048)
			(stroke
				(width 0.1)
				(type default)
			)
			(layer "F.Fab")
		)
		(fp_line
			(start -0.12065 0.3048)
			(end -0.67945 0.3048)
			(stroke
				(width 0.1)
				(type default)
			)
			(layer "F.Fab")
		)
		(fp_line
			(start 0.120396 0.2794)
			(end -0.12065 0.2794)
			(stroke
				(width 0.1)
				(type default)
			)
			(layer "F.Fab")
		)
		(fp_line
			(start 0.120396 0.3048)
			(end 0.120396 0.2794)
			(stroke
				(width 0.1)
				(type default)
			)
			(layer "F.Fab")
		)
		(fp_line
			(start 0.12065 -0.3048)
			(end 0.67945 -0.3048)
			(stroke
				(width 0.1)
				(type default)
			)
			(layer "F.Fab")
		)
		(fp_line
			(start 0.12065 -0.2794)
			(end 0.12065 -0.3048)
			(stroke
				(width 0.1)
				(type default)
			)
			(layer "F.Fab")
		)
		(fp_line
			(start 0.67945 -0.3048)
			(end 0.67945 0.3048)
			(stroke
				(width 0.1)
				(type default)
			)
			(layer "F.Fab")
		)
		(fp_line
			(start 0.67945 0.3048)
			(end 0.120396 0.3048)
			(stroke
				(width 0.1)
				(type default)
			)
			(layer "F.Fab")
		)
		(pad "1" smd circle
			(at -0.40005 0)
			(size 0 0)
			(layers "F.Cu" "F.Mask" "F.Paste")
			(net "PWRGD_P3V3_SSD10_D")
		)
		(pad "2" smd circle
			(at 0.40005 0)
			(size 0 0)
			(layers "F.Cu" "F.Mask" "F.Paste")
			(net "PWRGD_P3V3_SSD10_R")
		)
	)
	(footprint ""
		(layer "F.Cu")
		(at 146.18208 -296.191432 180)
		(property "Reference" "C3204"
			(at 0 0 180)
			(layer "F.SilkS")
			(hide yes)
			(effects
				(font
					(size 1.27 1.27)
				)
			)
		)
		(property "Value" ""
			(at 0 0 180)
			(layer "F.Fab")
			(effects
				(font
					(size 1.27 1.27)
				)
			)
		)
		(duplicate_pad_numbers_are_jumpers no)
		(fp_line
			(start 1.2954 0.5842)
			(end -1.2954 0.5842)
			(stroke
				(width 0.1524)
				(type default)
			)
			(layer "F.SilkS")
		)
		(fp_line
			(start 1.2954 -0.5842)
			(end 1.2954 0.5842)
			(stroke
				(width 0.1524)
				(type default)
			)
			(layer "F.SilkS")
		)
		(fp_line
			(start -1.2954 0.5842)
			(end -1.2954 -0.5842)
			(stroke
				(width 0.1524)
				(type default)
			)
			(layer "F.SilkS")
		)
		(fp_line
			(start -1.2954 -0.5842)
			(end 1.2954 -0.5842)
			(stroke
				(width 0.1524)
				(type default)
			)
			(layer "F.SilkS")
		)
		(fp_line
			(start 1.1938 0.4064)
			(end 0.8636 0.4064)
			(stroke
				(width 0.1)
				(type default)
			)
			(layer "F.Fab")
		)
		(fp_line
			(start 1.1938 -0.4064)
			(end 1.1938 0.4064)
			(stroke
				(width 0.1)
				(type default)
			)
			(layer "F.Fab")
		)
		(fp_line
			(start 0.8636 0.4572)
			(end -0.8636 0.4572)
			(stroke
				(width 0.1)
				(type default)
			)
			(layer "F.Fab")
		)
		(fp_line
			(start 0.8636 0.4064)
			(end 0.8636 0.4572)
			(stroke
				(width 0.1)
				(type default)
			)
			(layer "F.Fab")
		)
		(fp_line
			(start 0.8636 -0.4064)
			(end 1.1938 -0.4064)
			(stroke
				(width 0.1)
				(type default)
			)
			(layer "F.Fab")
		)
		(fp_line
			(start 0.8636 -0.4572)
			(end 0.8636 -0.4064)
			(stroke
				(width 0.1)
				(type default)
			)
			(layer "F.Fab")
		)
		(fp_line
			(start -0.8636 0.4572)
			(end -0.8636 0.4064)
			(stroke
				(width 0.1)
				(type default)
			)
			(layer "F.Fab")
		)
		(fp_line
			(start -0.8636 0.4064)
			(end -1.1938 0.4064)
			(stroke
				(width 0.1)
				(type default)
			)
			(layer "F.Fab")
		)
		(fp_line
			(start -0.8636 -0.4064)
			(end -0.8636 -0.4572)
			(stroke
				(width 0.1)
				(type default)
			)
			(layer "F.Fab")
		)
		(fp_line
			(start -0.8636 -0.4572)
			(end 0.8636 -0.4572)
			(stroke
				(width 0.1)
				(type default)
			)
			(layer "F.Fab")
		)
		(fp_line
			(start -1.1938 0.4064)
			(end -1.1938 -0.4064)
			(stroke
				(width 0.1)
				(type default)
			)
			(layer "F.Fab")
		)
		(fp_line
			(start -1.1938 -0.4064)
			(end -0.8636 -0.4064)
			(stroke
				(width 0.1)
				(type default)
			)
			(layer "F.Fab")
		)
		(pad "1" smd rect
			(at -0.7366 0 90)
			(size 0.7112 0.8128)
			(layers "F.Cu" "F.Mask" "F.Paste")
			(net "PCEPLL0_VDDA18_PEX1_R")
		)
		(pad "2" smd rect
			(at 0.7366 0 90)
			(size 0.7112 0.8128)
			(layers "F.Cu" "F.Mask" "F.Paste")
			(net "GND")
		)
	)
	(footprint ""
		(layer "F.Cu")
		(at 460.103728 -310.695086 180)
		(property "Reference" "PR181"
			(at 0 0 180)
			(layer "F.SilkS")
			(hide yes)
			(effects
				(font
					(size 1.27 1.27)
				)
			)
		)
		(property "Value" ""
			(at 0 0 180)
			(layer "F.Fab")
			(effects
				(font
					(size 1.27 1.27)
				)
			)
		)
		(duplicate_pad_numbers_are_jumpers no)
		(fp_line
			(start 0.7874 0.4064)
			(end -0.7874 0.4064)
			(stroke
				(width 0.1524)
				(type default)
			)
			(layer "F.SilkS")
		)
		(fp_line
			(start 0.7874 -0.4064)
			(end 0.7874 0.4064)
			(stroke
				(width 0.1524)
				(type default)
			)
			(layer "F.SilkS")
		)
		(fp_line
			(start -0.7874 0.4064)
			(end -0.7874 -0.4064)
			(stroke
				(width 0.1524)
				(type default)
			)
			(layer "F.SilkS")
		)
		(fp_line
			(start -0.7874 -0.4064)
			(end 0.7874 -0.4064)
			(stroke
				(width 0.1524)
				(type default)
			)
			(layer "F.SilkS")
		)
		(fp_line
			(start 0.67945 0.3048)
			(end 0.120396 0.3048)
			(stroke
				(width 0.1)
				(type default)
			)
			(layer "F.Fab")
		)
		(fp_line
			(start 0.67945 -0.3048)
			(end 0.67945 0.3048)
			(stroke
				(width 0.1)
				(type default)
			)
			(layer "F.Fab")
		)
		(fp_line
			(start 0.12065 -0.2794)
			(end 0.12065 -0.3048)
			(stroke
				(width 0.1)
				(type default)
			)
			(layer "F.Fab")
		)
		(fp_line
			(start 0.12065 -0.3048)
			(end 0.67945 -0.3048)
			(stroke
				(width 0.1)
				(type default)
			)
			(layer "F.Fab")
		)
		(fp_line
			(start 0.120396 0.3048)
			(end 0.120396 0.2794)
			(stroke
				(width 0.1)
				(type default)
			)
			(layer "F.Fab")
		)
		(fp_line
			(start 0.120396 0.2794)
			(end -0.12065 0.2794)
			(stroke
				(width 0.1)
				(type default)
			)
			(layer "F.Fab")
		)
		(fp_line
			(start -0.12065 0.3048)
			(end -0.67945 0.3048)
			(stroke
				(width 0.1)
				(type default)
			)
			(layer "F.Fab")
		)
		(fp_line
			(start -0.12065 0.2794)
			(end -0.12065 0.3048)
			(stroke
				(width 0.1)
				(type default)
			)
			(layer "F.Fab")
		)
		(fp_line
			(start -0.12065 -0.2794)
			(end 0.12065 -0.2794)
			(stroke
				(width 0.1)
				(type default)
			)
			(layer "F.Fab")
		)
		(fp_line
			(start -0.12065 -0.305054)
			(end -0.12065 -0.2794)
			(stroke
				(width 0.1)
				(type default)
			)
			(layer "F.Fab")
		)
		(fp_line
			(start -0.67945 0.3048)
			(end -0.67945 -0.305054)
			(stroke
				(width 0.1)
				(type default)
			)
			(layer "F.Fab")
		)
		(fp_line
			(start -0.67945 -0.305054)
			(end -0.12065 -0.305054)
			(stroke
				(width 0.1)
				(type default)
			)
			(layer "F.Fab")
		)
		(pad "1" smd circle
			(at -0.40005 0 180)
			(size 0 0)
			(layers "F.Cu" "F.Mask" "F.Paste")
			(net "SH_P1V25_PEX3_FB_P")
		)
		(pad "2" smd circle
			(at 0.40005 0 180)
			(size 0 0)
			(layers "F.Cu" "F.Mask" "F.Paste")
			(net "P1V25_PEX3_FB")
		)
	)
	(footprint ""
		(layer "F.Cu")
		(at 394.875512 -69.47916 180)
		(property "Reference" "PU116"
			(at -1.975358 4.07924 90)
			(unlocked yes)
			(layer "F.SilkS")
			(effects
				(font
					(size 0.7874 0.5842)
					(thickness 0.1524)
				)
			)
		)
		(property "Value" ""
			(at 0 0 180)
			(layer "F.Fab")
			(effects
				(font
					(size 1.27 1.27)
				)
			)
		)
		(duplicate_pad_numbers_are_jumpers no)
		(fp_line
			(start 1.239774 1.495298)
			(end -1.239774 1.495298)
			(stroke
				(width 0.1524)
				(type default)
			)
			(layer "F.SilkS")
		)
		(fp_line
			(start 1.239774 -1.495298)
			(end 1.239774 1.495298)
			(stroke
				(width 0.1524)
				(type default)
			)
			(layer "F.SilkS")
		)
		(fp_line
			(start -1.239774 1.495298)
			(end -1.239774 -1.495298)
			(stroke
				(width 0.1524)
				(type default)
			)
			(layer "F.SilkS")
		)
		(fp_line
			(start -1.239774 -1.495298)
			(end 1.239774 -1.495298)
			(stroke
				(width 0.1524)
				(type default)
			)
			(layer "F.SilkS")
		)
		(fp_poly
			(pts
				(xy -2.061972 -2.668778) (xy -2.780538 -1.950466) (xy -1.702816 -1.59131)
			)
			(stroke
				(width 0)
				(type default)
			)
			(fill yes)
			(layer "F.SilkS")
		)
		(fp_line
			(start 0.8001 1.050036)
			(end -0.8001 1.050036)
			(stroke
				(width 0.1)
				(type default)
			)
			(layer "F.Fab")
		)
		(fp_line
			(start 0.8001 -1.050036)
			(end 0.8001 1.050036)
			(stroke
				(width 0.1)
				(type default)
			)
			(layer "F.Fab")
		)
		(fp_line
			(start -0.8001 1.050036)
			(end -0.8001 -1.050036)
			(stroke
				(width 0.1)
				(type default)
			)
			(layer "F.Fab")
		)
		(fp_line
			(start -0.8001 -1.050036)
			(end 0.8001 -1.050036)
			(stroke
				(width 0.1)
				(type default)
			)
			(layer "F.Fab")
		)
		(fp_poly
			(pts
				(xy -2.458974 -0.508) (xy -2.458974 0.508) (xy -1.442974 0)
			)
			(stroke
				(width 0)
				(type default)
			)
			(fill yes)
			(layer "F.Fab")
		)
		(pad "1_2" smd circle
			(at -0.374904 0 270)
			(size 0 0)
			(layers "F.Cu" "F.Mask" "F.Paste")
			(net "P12V_AUX")
		)
		(pad "3" smd rect
			(at -0.499872 0.999998 180)
			(size 0.254 0.7112)
			(layers "F.Cu" "F.Mask" "F.Paste")
			(net "GND")
		)
		(pad "4" smd rect
			(at 0 0.999998 180)
			(size 0.254 0.7112)
			(layers "F.Cu" "F.Mask" "F.Paste")
			(net "P12V_SSD13_CO_ILIMIT")
		)
		(pad "5" smd rect
			(at 0.499872 0.999998 180)
			(size 0.254 0.7112)
			(layers "F.Cu" "F.Mask" "F.Paste")
			(net "P12V_SSD13_CO_MODE")
		)
		(pad "6_7" smd circle
			(at 0.374904 0 90)
			(size 0 0)
			(layers "F.Cu" "F.Mask" "F.Paste")
			(net "P12V_SSD13_R")
		)
		(pad "8" smd rect
			(at 0.499872 -0.999998 180)
			(size 0.254 0.7112)
			(layers "F.Cu" "F.Mask" "F.Paste")
			(net "P12V_SSD13_CO_GATE")
		)
		(pad "9" smd rect
			(at 0 -0.999998 180)
			(size 0.254 0.7112)
			(layers "F.Cu" "F.Mask" "F.Paste")
			(net "P12V_SSD13_CO_EN")
		)
		(pad "10" smd rect
			(at -0.499872 -0.999998 180)
			(size 0.254 0.7112)
			(layers "F.Cu" "F.Mask" "F.Paste")
			(net "P12V_SSD13_CO_DV_DT")
		)
	)
	(footprint ""
		(layer "F.Cu")
		(at 338.492592 -9.139682 180)
		(property "Reference" "C2739"
			(at 0 0 180)
			(layer "F.SilkS")
			(hide yes)
			(effects
				(font
					(size 1.27 1.27)
				)
			)
		)
		(property "Value" ""
			(at 0 0 180)
			(layer "F.Fab")
			(effects
				(font
					(size 1.27 1.27)
				)
			)
		)
		(duplicate_pad_numbers_are_jumpers no)
		(fp_line
			(start 0.7874 0.4064)
			(end -0.7874 0.4064)
			(stroke
				(width 0.1524)
				(type default)
			)
			(layer "F.SilkS")
		)
		(fp_line
			(start 0.7874 -0.4064)
			(end 0.7874 0.4064)
			(stroke
				(width 0.1524)
				(type default)
			)
			(layer "F.SilkS")
		)
		(fp_line
			(start -0.7874 0.4064)
			(end -0.7874 -0.4064)
			(stroke
				(width 0.1524)
				(type default)
			)
			(layer "F.SilkS")
		)
		(fp_line
			(start -0.7874 -0.4064)
			(end 0.7874 -0.4064)
			(stroke
				(width 0.1524)
				(type default)
			)
			(layer "F.SilkS")
		)
		(fp_line
			(start 0.67945 0.3048)
			(end 0.120396 0.3048)
			(stroke
				(width 0.1)
				(type default)
			)
			(layer "F.Fab")
		)
		(fp_line
			(start 0.67945 -0.3048)
			(end 0.67945 0.3048)
			(stroke
				(width 0.1)
				(type default)
			)
			(layer "F.Fab")
		)
		(fp_line
			(start 0.12065 -0.2794)
			(end 0.12065 -0.3048)
			(stroke
				(width 0.1)
				(type default)
			)
			(layer "F.Fab")
		)
		(fp_line
			(start 0.12065 -0.3048)
			(end 0.67945 -0.3048)
			(stroke
				(width 0.1)
				(type default)
			)
			(layer "F.Fab")
		)
		(fp_line
			(start 0.120396 0.3048)
			(end 0.120396 0.2794)
			(stroke
				(width 0.1)
				(type default)
			)
			(layer "F.Fab")
		)
		(fp_line
			(start 0.120396 0.2794)
			(end -0.12065 0.2794)
			(stroke
				(width 0.1)
				(type default)
			)
			(layer "F.Fab")
		)
		(fp_line
			(start -0.12065 0.3048)
			(end -0.67945 0.3048)
			(stroke
				(width 0.1)
				(type default)
			)
			(layer "F.Fab")
		)
		(fp_line
			(start -0.12065 0.2794)
			(end -0.12065 0.3048)
			(stroke
				(width 0.1)
				(type default)
			)
			(layer "F.Fab")
		)
		(fp_line
			(start -0.12065 -0.2794)
			(end 0.12065 -0.2794)
			(stroke
				(width 0.1)
				(type default)
			)
			(layer "F.Fab")
		)
		(fp_line
			(start -0.12065 -0.305054)
			(end -0.12065 -0.2794)
			(stroke
				(width 0.1)
				(type default)
			)
			(layer "F.Fab")
		)
		(fp_line
			(start -0.67945 0.3048)
			(end -0.67945 -0.305054)
			(stroke
				(width 0.1)
				(type default)
			)
			(layer "F.Fab")
		)
		(fp_line
			(start -0.67945 -0.305054)
			(end -0.12065 -0.305054)
			(stroke
				(width 0.1)
				(type default)
			)
			(layer "F.Fab")
		)
		(pad "1" smd circle
			(at -0.40005 0 180)
			(size 0 0)
			(layers "F.Cu" "F.Mask" "F.Paste")
			(net "GND")
		)
		(pad "2" smd circle
			(at 0.40005 0 180)
			(size 0 0)
			(layers "F.Cu" "F.Mask" "F.Paste")
			(net "P3V3_AUX")
		)
	)
	(footprint ""
		(layer "F.Cu")
		(at 169.562526 -22.937216 90)
		(property "Reference" "R1670"
			(at 0 0 90)
			(layer "F.SilkS")
			(hide yes)
			(effects
				(font
					(size 1.27 1.27)
				)
			)
		)
		(property "Value" ""
			(at 0 0 90)
			(layer "F.Fab")
			(effects
				(font
					(size 1.27 1.27)
				)
			)
		)
		(duplicate_pad_numbers_are_jumpers no)
		(fp_line
			(start 0.7874 -0.4064)
			(end 0.7874 0.4064)
			(stroke
				(width 0.1524)
				(type default)
			)
			(layer "F.SilkS")
		)
		(fp_line
			(start -0.7874 -0.4064)
			(end 0.7874 -0.4064)
			(stroke
				(width 0.1524)
				(type default)
			)
			(layer "F.SilkS")
		)
		(fp_line
			(start 0.7874 0.4064)
			(end -0.7874 0.4064)
			(stroke
				(width 0.1524)
				(type default)
			)
			(layer "F.SilkS")
		)
		(fp_line
			(start -0.7874 0.4064)
			(end -0.7874 -0.4064)
			(stroke
				(width 0.1524)
				(type default)
			)
			(layer "F.SilkS")
		)
		(fp_line
			(start -0.12065 -0.305054)
			(end -0.12065 -0.2794)
			(stroke
				(width 0.1)
				(type default)
			)
			(layer "F.Fab")
		)
		(fp_line
			(start -0.67945 -0.305054)
			(end -0.12065 -0.305054)
			(stroke
				(width 0.1)
				(type default)
			)
			(layer "F.Fab")
		)
		(fp_line
			(start 0.67945 -0.3048)
			(end 0.67945 0.3048)
			(stroke
				(width 0.1)
				(type default)
			)
			(layer "F.Fab")
		)
		(fp_line
			(start 0.12065 -0.3048)
			(end 0.67945 -0.3048)
			(stroke
				(width 0.1)
				(type default)
			)
			(layer "F.Fab")
		)
		(fp_line
			(start 0.12065 -0.2794)
			(end 0.12065 -0.3048)
			(stroke
				(width 0.1)
				(type default)
			)
			(layer "F.Fab")
		)
		(fp_line
			(start -0.12065 -0.2794)
			(end 0.12065 -0.2794)
			(stroke
				(width 0.1)
				(type default)
			)
			(layer "F.Fab")
		)
		(fp_line
			(start 0.120396 0.2794)
			(end -0.12065 0.2794)
			(stroke
				(width 0.1)
				(type default)
			)
			(layer "F.Fab")
		)
		(fp_line
			(start -0.12065 0.2794)
			(end -0.12065 0.3048)
			(stroke
				(width 0.1)
				(type default)
			)
			(layer "F.Fab")
		)
		(fp_line
			(start 0.67945 0.3048)
			(end 0.120396 0.3048)
			(stroke
				(width 0.1)
				(type default)
			)
			(layer "F.Fab")
		)
		(fp_line
			(start 0.120396 0.3048)
			(end 0.120396 0.2794)
			(stroke
				(width 0.1)
				(type default)
			)
			(layer "F.Fab")
		)
		(fp_line
			(start -0.12065 0.3048)
			(end -0.67945 0.3048)
			(stroke
				(width 0.1)
				(type default)
			)
			(layer "F.Fab")
		)
		(fp_line
			(start -0.67945 0.3048)
			(end -0.67945 -0.305054)
			(stroke
				(width 0.1)
				(type default)
			)
			(layer "F.Fab")
		)
		(pad "1" smd circle
			(at -0.40005 0 90)
			(size 0 0)
			(layers "F.Cu" "F.Mask" "F.Paste")
			(net "SMB_BIC_I2C9_MUX0_SSD5_R_SDA")
		)
		(pad "2" smd circle
			(at 0.40005 0 90)
			(size 0 0)
			(layers "F.Cu" "F.Mask" "F.Paste")
			(net "SMB_ISO_SSD5_SDA")
		)
	)
)
